# T6G (Grand Teton) — schematic netlist excerpt (pin names and nets, part order shuffled) for the footprints in the layout excerpt that follows; sources: Cadence DE-HDL packaged netlist, KiCad conversion of 04192023_DAF0TMB3IC0_F0TG_MB_C_brd_V02_OCP.brd

R2121  Q_RES  4.7K 5% CHIP  pkg 0402LF  page 144 : A = P3V3_AUX ; B = RST_PERST_BUF_M2_0_N
PC479  Q_CAP  0.1UF 25V 10% X7R  pkg 0402  page 194 : A = P12V_AUX ; B = GND

(kicad_pcb
	(version 20260206)
	(generator "pcbnew")
	(generator_version "10.0")
	(general
		(thickness 1.6)
		(legacy_teardrops no)
	)
	(paper "A4")
	(title_block
		(title "04192023_DAF0TMB3IC0_F0TG_MB_C_brd_V02_OCP.brd")
		(comment 1 "Grand Teton / footprints 2571-2572 of 8354")
	)
	(layers
		(0 "F.Cu" signal "TOP")
		(4 "In1.Cu" signal "GND")
		(6 "In2.Cu" signal "IN1")
		(8 "In3.Cu" signal "GND1")
		(10 "In4.Cu" signal "IN2")
		(12 "In5.Cu" signal "GND2")
		(14 "In6.Cu" signal "IN3")
		(16 "In7.Cu" signal "GND3")
		(18 "In8.Cu" signal "VCC")
		(20 "In9.Cu" signal "VCC1")
		(22 "In10.Cu" signal "GND4")
		(24 "In11.Cu" signal "IN4")
		(26 "In12.Cu" signal "GND5")
		(28 "In13.Cu" signal "IN5")
		(30 "In14.Cu" signal "GND6")
		(32 "In15.Cu" signal "IN6")
		(34 "In16.Cu" signal "GND7")
		(2 "B.Cu" signal "BOTTOM")
		(9 "F.Adhes" user "F.Adhesive")
		(11 "B.Adhes" user "B.Adhesive")
		(13 "F.Paste" user "Package Geometry/Pastemask Top")
		(15 "B.Paste" user "Package Geometry/Pastemask Bottom")
		(5 "F.SilkS" user "Ref Des/Silkscreen Top")
		(7 "B.SilkS" user "Ref Des/Silkscreen Bottom")
		(1 "F.Mask" user "Board Geometry/Soldermask Top")
		(3 "B.Mask" user "Board Geometry/Soldermask Bottom")
		(17 "Dwgs.User" user "User.Drawings")
		(19 "Cmts.User" user "User.Comments")
		(21 "Eco1.User" user "User.Eco1")
		(23 "Eco2.User" user "User.Eco2")
		(25 "Edge.Cuts" user "Board Geometry/Outline")
		(27 "Margin" user)
		(31 "F.CrtYd" user "Package Geometry/Place Bound Top")
		(29 "B.CrtYd" user "Package Geometry/Place Bound Bottom")
		(35 "F.Fab" user "Ref Des/Assembly Top")
		(33 "B.Fab" user "Ref Des/Assembly Bottom")
	)
	(footprint ""
		(layer "F.Cu")
		(at 140.886942 -101.494844)
		(property "Reference" "R2121"
			(at 0 0 0)
			(layer "F.SilkS")
			(hide yes)
			(effects
				(font
					(size 1.27 1.27)
				)
			)
		)
		(property "Value" ""
			(at 0 0 0)
			(layer "F.Fab")
			(effects
				(font
					(size 1.27 1.27)
				)
			)
		)
		(duplicate_pad_numbers_are_jumpers no)
		(fp_line
			(start -0.7874 -0.4064)
			(end 0.7874 -0.4064)
			(stroke
				(width 0.1524)
				(type default)
			)
			(layer "F.SilkS")
		)
		(fp_line
			(start -0.7874 0.4064)
			(end -0.7874 -0.4064)
			(stroke
				(width 0.1524)
				(type default)
			)
			(layer "F.SilkS")
		)
		(fp_line
			(start 0.7874 -0.4064)
			(end 0.7874 0.4064)
			(stroke
				(width 0.1524)
				(type default)
			)
			(layer "F.SilkS")
		)
		(fp_line
			(start 0.7874 0.4064)
			(end -0.7874 0.4064)
			(stroke
				(width 0.1524)
				(type default)
			)
			(layer "F.SilkS")
		)
		(fp_line
			(start -0.67945 -0.305054)
			(end -0.12065 -0.305054)
			(stroke
				(width 0.1)
				(type default)
			)
			(layer "F.Fab")
		)
		(fp_line
			(start -0.67945 0.3048)
			(end -0.67945 -0.305054)
			(stroke
				(width 0.1)
				(type default)
			)
			(layer "F.Fab")
		)
		(fp_line
			(start -0.12065 -0.305054)
			(end -0.12065 -0.2794)
			(stroke
				(width 0.1)
				(type default)
			)
			(layer "F.Fab")
		)
		(fp_line
			(start -0.12065 -0.2794)
			(end 0.12065 -0.2794)
			(stroke
				(width 0.1)
				(type default)
			)
			(layer "F.Fab")
		)
		(fp_line
			(start -0.12065 0.2794)
			(end -0.12065 0.3048)
			(stroke
				(width 0.1)
				(type default)
			)
			(layer "F.Fab")
		)
		(fp_line
			(start -0.12065 0.3048)
			(end -0.67945 0.3048)
			(stroke
				(width 0.1)
				(type default)
			)
			(layer "F.Fab")
		)
		(fp_line
			(start 0.120396 0.2794)
			(end -0.12065 0.2794)
			(stroke
				(width 0.1)
				(type default)
			)
			(layer "F.Fab")
		)
		(fp_line
			(start 0.120396 0.3048)
			(end 0.120396 0.2794)
			(stroke
				(width 0.1)
				(type default)
			)
			(layer "F.Fab")
		)
		(fp_line
			(start 0.12065 -0.3048)
			(end 0.67945 -0.3048)
			(stroke
				(width 0.1)
				(type default)
			)
			(layer "F.Fab")
		)
		(fp_line
			(start 0.12065 -0.2794)
			(end 0.12065 -0.3048)
			(stroke
				(width 0.1)
				(type default)
			)
			(layer "F.Fab")
		)
		(fp_line
			(start 0.67945 -0.3048)
			(end 0.67945 0.3048)
			(stroke
				(width 0.1)
				(type default)
			)
			(layer "F.Fab")
		)
		(fp_line
			(start 0.67945 0.3048)
			(end 0.120396 0.3048)
			(stroke
				(width 0.1)
				(type default)
			)
			(layer "F.Fab")
		)
		(pad "1" smd circle
			(at -0.40005 0)
			(size 0 0)
			(layers "F.Cu" "F.Mask" "F.Paste")
			(net "P3V3_AUX")
		)
		(pad "2" smd circle
			(at 0.40005 0)
			(size 0 0)
			(layers "F.Cu" "F.Mask" "F.Paste")
			(net "RST_PERST_BUF_M2_0_N")
		)
	)
	(footprint ""
		(layer "F.Cu")
		(at 366.202214 -151.857964 -90)
		(property "Reference" "PC479"
			(at 0 0 270)
			(layer "F.SilkS")
			(hide yes)
			(effects
				(font
					(size 1.27 1.27)
				)
			)
		)
		(property "Value" ""
			(at 0 0 270)
			(layer "F.Fab")
			(effects
				(font
					(size 1.27 1.27)
				)
			)
		)
		(duplicate_pad_numbers_are_jumpers no)
		(fp_line
			(start -0.7874 0.4064)
			(end -0.7874 -0.4064)
			(stroke
				(width 0.1524)
				(type default)
			)
			(layer "F.SilkS")
		)
		(fp_line
			(start 0.7874 0.4064)
			(end -0.7874 0.4064)
			(stroke
				(width 0.1524)
				(type default)
			)
			(layer "F.SilkS")
		)
		(fp_line
			(start -0.7874 -0.4064)
			(end 0.7874 -0.4064)
			(stroke
				(width 0.1524)
				(type default)
			)
			(layer "F.SilkS")
		)
		(fp_line
			(start 0.7874 -0.4064)
			(end 0.7874 0.4064)
			(stroke
				(width 0.1524)
				(type default)
			)
			(layer "F.SilkS")
		)
		(fp_line
			(start -0.67945 0.3048)
			(end -0.67945 -0.305054)
			(stroke
				(width 0.1)
				(type default)
			)
			(layer "F.Fab")
		)
		(fp_line
			(start -0.12065 0.3048)
			(end -0.67945 0.3048)
			(stroke
				(width 0.1)
				(type default)
			)
			(layer "F.Fab")
		)
		(fp_line
			(start 0.120396 0.3048)
			(end 0.120396 0.2794)
			(stroke
				(width 0.1)
				(type default)
			)
			(layer "F.Fab")
		)
		(fp_line
			(start 0.67945 0.3048)
			(end 0.120396 0.3048)
			(stroke
				(width 0.1)
				(type default)
			)
			(layer "F.Fab")
		)
		(fp_line
			(start -0.12065 0.2794)
			(end -0.12065 0.3048)
			(stroke
				(width 0.1)
				(type default)
			)
			(layer "F.Fab")
		)
		(fp_line
			(start 0.120396 0.2794)
			(end -0.12065 0.2794)
			(stroke
				(width 0.1)
				(type default)
			)
			(layer "F.Fab")
		)
		(fp_line
			(start -0.12065 -0.2794)
			(end 0.12065 -0.2794)
			(stroke
				(width 0.1)
				(type default)
			)
			(layer "F.Fab")
		)
		(fp_line
			(start 0.12065 -0.2794)
			(end 0.12065 -0.3048)
			(stroke
				(width 0.1)
				(type default)
			)
			(layer "F.Fab")
		)
		(fp_line
			(start 0.12065 -0.3048)
			(end 0.67945 -0.3048)
			(stroke
				(width 0.1)
				(type default)
			)
			(layer "F.Fab")
		)
		(fp_line
			(start 0.67945 -0.3048)
			(end 0.67945 0.3048)
			(stroke
				(width 0.1)
				(type default)
			)
			(layer "F.Fab")
		)
		(fp_line
			(start -0.67945 -0.305054)
			(end -0.12065 -0.305054)
			(stroke
				(width 0.1)
				(type default)
			)
			(layer "F.Fab")
		)
		(fp_line
			(start -0.12065 -0.305054)
			(end -0.12065 -0.2794)
			(stroke
				(width 0.1)
				(type default)
			)
			(layer "F.Fab")
		)
		(pad "1" smd circle
			(at -0.40005 0 270)
			(size 0 0)
			(layers "F.Cu" "F.Mask" "F.Paste")
			(net "P12V_AUX")
		)
		(pad "2" smd circle
			(at 0.40005 0 270)
			(size 0 0)
			(layers "F.Cu" "F.Mask" "F.Paste")
			(net "GND")
		)
	)
)
